 
 
 
 
 
 
 
 
      Honey Badger 
         User Manual 
 
         
 
                
 
 
 
 
Version 1.7 
 December 2015 
 
Copyright ©  2015 Wiwynn. All rights reserved. 
 


                                                               
 
 
2 Wiwynn Honey Badger User Manual 
Copyright  
Copyright ©  2015 by Wiwynn Corporation. All rights reserved. No 
part of this publication may be reproduced, transmitted, 
transcribed, stored in a retrieval system, or translated into any 
language or computer language, in any form or by any means, 
electronic, mechanical, magnetic, optical, chemical, manual or 
otherwise, without the prior written permission of Wiwynn 
Corporation.  
Disclaimer  
The information in this guide is subject to change without notice.  
Wiwynn Corporation makes no representations or warranties, 
either expressed or implied, with respect to the contents hereof 
and specifically disclaims any warranties of merchantability or 
fitness for any particular purpose. Any Wiwynn Corporation 
software described in this manual is sold or licensed "as is". 
Should the programs prove defective following their purchase, the 
buyer (and not Wiwynn Corporation, its distributor, or its dealer) 
assumes the entire cost of all necessary servicing, repair, and any 
incidental or consequential damages resulting from any defect in 
the software.



                          
 
 
Wiwyynn Honey Badger User Manual 3 
Revision History 
Date Version Changes 
2015/01/06 1.0 First release 
2015/01/22 1.1 Used new Panther+ board, LSI 
baseboard and SAS expander board. 
New photos in section 3.22 Debug Card.  
2015/02/10 1.1 Added Battery Warning in section 3.13 
2015/03/13 1.2 Added item 7 in section 3.1. 
2015/04/28 1.3 Revised sections 2.1, 2.4, 3.22, 3.9.1, 
3.12.1 and 5.2. 
2015/05/08 1.3 Change PCIE CONN to GF1 in section 
2.4 
2015/05/26 1.4 Revised sections 3.7 and 3.11. 
2015/11/20 1.5 Added Chapter 4 Firmware Update 
2015/12/02 1.6 Update Section 2.1 System Specification 
2015/12/24 1.7 1.  Updated BMC and BIOS firmware 
updates in Chapter 4.  
2. Added 4. Expander Firmware 
Update via in-band SAS Interface in 
Chapter 4. 
   
 
  



                                                               
 
 
4 Wiwynn Honey Badger User Manual 
Contents 
1. Preface.............................................................................................. 6 
1.1 Introduction ............................................................................ 6 
1.2 About this Manual ................................................................... 6 
2. System Tour ..................................................................................... 7 
2.1 System Specification .............................................................. 7 
2.2 Front Panel ............................................................................. 7 
2.3 Rear Panel ............................................................................. 9 
2.4 SAS Expander Board ........................................................... 10 
2.5 Panther+ Board .................................................................... 12 
2.6 LSI Baseboard...................................................................... 14 
2.7 Drive Plane Board ................................................................ 15 
2.8 Fan Controller Board ............................................................ 17 
3. System Upgrades .......................................................................... 18 
3.1 Safety instructions ................................................................ 18 
3.2 Recommended Tools ........................................................... 20 
3.3 Replacing the Side Ear Brackets .......................................... 21 
3.4 Replacing the System .......................................................... 23 
3.5 Opening the System ............................................................. 27 
3.6 Replacing the System Fans ................................................. 29 
3.7 Replacing the Panther+ Board ............................................. 31 
3.8 Replacing the Memory ......................................................... 34 
3.9 Replacing the mSATA SSD Module ..................................... 36 
3.10 Replacing the M.2 SSD Module ........................................... 38 
3.11 Replacing the LSI Baseboard ............................................... 40 
3.12 Replacing the Mezzanine Card ............................................ 42 
3.13 Replacing the Battery ........................................................... 44 
3.14 Replacing the SAS Expander Board .................................... 46 



                          
 
 
Wiwyynn Honey Badger User Manual 5 
3.15 Replacing the Hard Disk Drives ........................................... 48 
3.16 Replacing the Power Cable .................................................. 52 
3.17 Replacing the HDD Tray ...................................................... 56 
3.18 Replacing the Bus Bar Cables ............................................. 61 
3.19 Replacing the Fan Controller Board ..................................... 65 
3.20 Replacing the Power Transition Board ................................. 68 
3.21 Replacing the Drive Plane Board ......................................... 72 
3.22 Debug Card .......................................................................... 74 
4. Firmware Update ........................................................................... 76 
5. Wiwynn Supported SES Pages .................................................... 80 
6. Checkpoints and Errors ................................................................ 91 
6.1 Error Code Definition ............................................................ 91 
6.2 Post Code Table................................................................... 98 
 
  



                                                               
 
 
6 Wiwynn Honey Badger User Manual 
1. Preface 
Designed to support up to thirty SAS and SATA hard drives in a 2U 
chassis, Honey Badger stands out from other storage servers with the 
highest storage density in the industry. In addition, Honey Badger is not 
just a storage subsystem but also a computing server with up to two Intel®  
Atom server nodes. 
1.1 Introduction 
Honey Badger supports high availability with hot-plug hard drives and 
redundant cooling. Its tool-less design makes it easy to maintain and 
replace. 
1.2 About this Manual 
The contents in this manual include: 
Chapter 2 – describes the system specification, front and rear 
components, and the different boards 
Chapter 3 – shows how to replace the system and system components 
Chapter 4 – shows how to update the firmware 
Chapter 5 – lists the Wiwynn supported SES pages 
Chapter 6 – lists the checkpoints and errors 
For more product information, please refer to: 
http://www.wiwynn.com/static/honeybadger.html 
  



                          
 
 
Wiwyynn Honey Badger User Manual 7 
2. System Tour  
2.1 System Specification 
2.2 Front Panel 
Node 
Processor Intel®  Atom C2700 series 
Memory Up to 32GB; 2GB/4GB/8GB DDR3 up to 
1600MT/s; 4 SODIMM slots 
Storage and IO 
Expander  SAS 12G Expander 
Storage Thirty 3.5" hot-plug drive bays: 
‧SAS HDD (10K rpm) 
‧Nearline SAS HDD (7.2K rpm) 
‧SATA HDD (7.2K rpm) 
One EXT mini-SAS 12G port 
Remote Management IPMI V2.0 compliant 
Remote Management Controller (option) 
Serial-over-LAN 
Expansion Slots One PCI-E x8 mezzanine slot with x4 signal: 
‧Single 10GbE SFP+ port 
Power Supply, Physical and Packaging Specifications 
Power Supply Centralized 12V DC bus bar 
Power Consumption 305W (Idle); 515W (Max) 
Form Factor and  
Dimensions 2 OU rack; 93.5 (H) * 536 (W) * 878 (D) (mm) 
Weight 38 kg ~ 55 kg 
OS Support List CentOS 6.x (64 bits) 



                                                               
 
 
8 Wiwynn Honey Badger User Manual 
The illustration below shows the system front panel. 
 
Item Component 
1 HDD Tray 1 
2 Mini-SAS External Connector 
3 HDD Tray 1 Primary Side 
4 USB Connector 
5 10G Card Connector 
6 Debug Card Connector 
7 Debug Card Connector 
8 HDD Tray 2 Primary Side 
9 Mini-SAS External Connector 
10 HDD Tray 2 
 
  


                          
 
 
Wiwyynn Honey Badger User Manual 9 
2.3 Rear Panel 
 
Item Component 
1 Fan 1 
2 Fan 2 
3 Fan 3 
4 Fan 4 
5 Fan 5 
6 Fan 6 
7 Top Cover Thumbscrews 
 
  


                                                               
 
 
10 Wiwynn Honey Badger User Manual 
2.4 SAS Expander Board 
 
 
Item Connector Description 
1 EXT SAS CONN External Mini-SAS Connector 
2 DEBUG Debug Card Connector 
3 GF1 Golden Finger 
 
 


                          
 
 
Wiwyynn Honey Badger User Manual 11 
2.4.1 SAS Expander Board LED Indicator Status 
 
Item LED Indicator LED 
Color 
LED State Status 
1 External Mini 
SAS LED 
 
 
Solid Blue SAS Links Healthy 
 
 
Solid Red Loss of SAS Links 
 
 
Off No SAS Links 
2 Internal Mini 
SAS LED 
 
  
Solid Blue SAS Links Healthy 
3 
 
 
 
Solid Red Loss of SAS Links 
 
  
Off No SAS Links 
4 Enclosure 
Status 
LED 
 
 
 
Solid Blue Normal System 
Operation 
 
  
Solid Red Any Error in 
Whole Enclosure 


                                                               
 
 
12 Wiwynn Honey Badger User Manual 
2.5 Panther+ Board 
2.5.1 Panther+ Board Top View 
 
 
Item Connector Description 
1 DDR CHB_0 DIMM3 Slot 
2 mSATA CONN mSATA Connector   
3 NGFF CONN NGFF M.2 Connector 
4 DDR CHA_0 DIMM1 Slot 
 
  


                          
 
 
Wiwyynn Honey Badger User Manual 13 
2.5.2 Panther+ Board Bottom View 
               
 
 
Item Connector Description 
1 GF1 Golden Finger 
2 DDR CHB_1 DIMM4 Slot 
3 DDR CHA_1 DIMM2 Slot 
 
  


                                                               
 
 
14 Wiwynn Honey Badger User Manual 
2.6 LSI Baseboard 
 
 
Item Connector Description 
1 CN1 External Mini-SAS Connector 
2 CN2 Internal Mini-SAS Connector 
3 CN8 Riser Card Connector 
4 SKT1 USB Port 
5 MEZCN1 Mezzanine Card Connector 
6 CN3 Debug Card Connector 
7 PWR Power Button 
8 RST Reset Button 
9 BAT1 RTC Battery Holder 
10 GF1 Golden Finger  
  


                          
 
 
Wiwyynn Honey Badger User Manual 15 
2.7 Drive Plane Board 
 
 
Item Connector Description 
1 STRADDLE 
CONN 
Straddle Connector 
2 HDD0 HDD0 Connector 
3 HDD1 HDD1 Connector 
4 HDD2 HDD2 Connector 
5 HDD3 HDD3 Connector 
6 HDD4 HDD4 Connector 
7 HDD5 HDD5 Connector 
8 HDD6 HDD6 Connector 
  


                                                               
 
 
16 Wiwynn Honey Badger User Manual 
Item Connector Description 
9 HDD7 HDD7 Connector 
10 HDD8 HDD8 Connector 
11 HDD9 HDD9 Connector 
12 HDD10 HDD10 Connector 
13 HDD11 HDD11 Connector 
14 HDD12 HDD12 Connector 
15 HDD13 HDD13 Connector 
16 HDD14 HDD14 Connector 
17 X1PCIE_A1 PCIE X1 Connector A for signals 
18 X16PCIE_A PCIE X16 Connector A for differential 
19 X1PCIE_A2 PCIE X1 Connector A for power 
20 X1PCIE_B1 PCIE X1 Connector B for signals 
21 X16PCIE_B PCIE X16 Connector B for differential 
22 X1PCIE_B2 PCIE X1 Connector B for power 
 
 
 
 
 
 
 
 
 
 



                          
 
 
Wiwyynn Honey Badger User Manual 17 
2.8 Fan Controller Board 
 
 
 
Item Connector Description 
1 FAN HEADER 1 Fan 1 Connector 
2 FAN HEADER 2 Fan 2 Connector 
3 FAN HEADER 3 Fan 3 Connector 
4 FAN HEADER 4 Fan 4 Connector 
5 FAN HEADER 5 Fan 5 Connector 
6 FAN HEADER 6 Fan 6 Connector 
7 CN9 Power Cable Connector 1 
8 CN10 Power Cable Connector 2 
 
  


                                                               
 
 
18 Wiwynn Honey Badger User Manual 
3. System Upgrades 
3.1 Safety instructions 
Read these instructions carefully. Keep this document for future 
reference. Follow all warnings and instructions for your safety and to 
avoid damaging the system. 
1 Use both hands on the Tray Handles at all times and keep the HDD 
tray in the horizontal position when pulling it out or pushing it in to 
avoid damaging the HDDs and SAS Expander Boards. 
2 To avoid any injury, do not hold and use the latches or other parts of 
the HDD Tray to pull out or push it in. 
3 For safety reason, after pulling out the HDD tray, keep holding the 
tray handles to prevent the HDD tray from dropping. 
4 HDD latches on the HDD tray may pop out if systems are 
inappropriately handled during transport, for example, if it dropped 
upside down. This will prevent you from pulling out the upper or 
lower HDD tray alone. To fix this, you need to pull out the two HDD 
trays together, find the HDD latches that popped out and press them 
back into place. If you still cannot pull out the HDD tray, DO NOT 
FORCE IT and contact Customer Service for assistance. 



                          
 
 
Wiwyynn Honey Badger User Manual 19 
 
5 When pulling the system out of the rack for performing system 
upgrade, maintenance and debug, make sure to always place the 
system in a flat rigid surface. 
 
Caution: DO NOT place the system on a foam pad or other 
non-rigid surface; doing so may cause the chassis to warp, 
damaging the SAS Expander Boards and damaging the drive plane 
board connectors while pulling out the HDD tray. 
6 Before you pull out one HDD Tray, make sure the other HDD Tray 
is latched and secured by latch handles. 
7 Caution: The power energy in your system have energy hazards 
which can cause bodily harm. Unless you are instructed otherwise, 
only TRAINED service technicians are authorized to remove the 
covers and access any of the components inside the system. 
Remove the power before executing any of the following 
processes: 
- Replacing the Power cable; or 
- Replacing the Bus Bar Cables; or 
- Replacing the Fan Controller Board. 


                                                               
 
 
20 Wiwynn Honey Badger User Manual 
3.2 Recommended Tools 
In performing the disassembly and assembly process, you will need the 
following tools: 
 Philips screwdriver 
 Flat screwdriver 
 Torx screwdriver 
 
  



                          
 
 
Wiwyynn Honey Badger User Manual 21 
3.3 Replacing the Side Ear Brackets 
The system is shipped with two side ear brackets installed as a safety 
precaution during transport. Remove the brackets before installing the 
system in its rack. 
3.3.1 Removing the Side Ear Brackets  
1 Remove the four screws securing the side ear brackets to the 
chassis. 
 
2 Detach the two side ear brackets from the chassis. 
 


                                                               
 
 
22 Wiwynn Honey Badger User Manual 
3.3.2 Installing the Side Ear Brackets 
1 Place the two side ear brackets into the chassis. 
 
2 Secure the side ear brackets to the chassis by using four screws. 
Tighten screws using 1.0 kgf-cm torque. Do not over-tighten 
screws; damage to the HDD trays may result. 
 


                          
 
 
Wiwyynn Honey Badger User Manual 23 
3.4 Replacing the System 
3.4.1 Removing the System from the Rack 
1 Lift the tabs to release the latch handles that secure the two HDD 
trays to the chassis. 
 
2 Slide the system slowly out of the rack using two hands.  
 


                                                               
 
 
24 Wiwynn Honey Badger User Manual 
3 When the latch handles clear the rack posts, return the latch 
handles to the lock position (1), then slide the system out of the 
rack (2). 
 
 
 
Caution: The system is very heavy. Use a server lift or at least two 
people to lift the system into or from the rack. 
  


                          
 
 
Wiwyynn Honey Badger User Manual 25 
3.4.2 Installing the System into the Rack 
1 Insert the system into the chassis (1), and then lift the tabs to 
release the latch handles (2). 
 
 
 
Caution: The system is very heavy. Use a server lift or at least two 
people to lift the system into or from the rack.  
  


                                                               
 
 
26 Wiwynn Honey Badger User Manual 
2 Push the system all the way into the rack. 
 
3 Push the latch handles until they lock into place. 
 


                          
 
 
Wiwyynn Honey Badger User Manual 27 
3.5 Opening the System 
3.5.1 Removing the Top Cover  
1 Remove the system from the rack (see Removing the System 
from the Rack on page 23). 
2 Loosen the two thumbscrews securing the top cover to the chassis. 
 
3 Slide the top cover towards the rear and lift it off the chassis. 
 


                                                               
 
 
28 Wiwynn Honey Badger User Manual 
3.5.2 Installing the Top Cover 
1 Lower the top cover onto the chassis and slide it towards the front 
until the thumbscrews are aligned with the screw holes. 
 
2 Secure the top cover to the chassis by tightening the two 
thumbscrews. 
 
3 Install the system into the rack (see Installing the System into the 
Rack on page 25).   


                          
 
 
Wiwyynn Honey Badger User Manual 29 
3.6 Replacing the System Fans 
3.6.1 Removing the Fan Module 
1 Remove the system from the rack (see Removing the System 
from the Rack on page 23). 
2 Loosen the thumbscrew securing the fan module to the chassis. 
 
3 Pull out the fan module (1) and lift it (2) off the chassis. 
 


                                                               
 
 
30 Wiwynn Honey Badger User Manual 
3.6.2 Installing the Fan Module 
1 Insert the fan module (1) and push (2) until it is seated firmly into 
the chassis. 
 
2 Secure the fan module to the chassis by tightening the 
thumbscrew. 
 
3 Install the system into the rack (see Installing the System into the 
Rack on page 25).  


                          
 
 
Wiwyynn Honey Badger User Manual 31 
3.7 Replacing the Panther+ Board 
 WARNING 
The heat sink on the bottom side of the Panther+ board 
may be hot. To avoid possible burns, do not touch the 
heat sink. 
 
 
CAUTION 
Panther+ board does not support hot-plug. Please 
follow the instructions in the following sections to 
remove/install the Panther+ board. Incorrect procedure 
may cause damages to the system and/or components. 
TiP To replace the Panther+ Board without having to turn 
off the system power, skip this section and proceed to 
section 3.11 Replacing the LSI Baseboard. 
3.7.1 Removing the Panther+ Board 
1 Make sure the system power is turned off.   
2 Unlock the clips securing the Panther+ board to the LSI baseboard. 
 
  


                                                               
 
 
32 Wiwynn Honey Badger User Manual 
3 Pull out the Panther+ board. 
 
 
  


                          
 
 
Wiwyynn Honey Badger User Manual 33 
3.7.2 Installing the Panther+ Board 
1 Make sure the system power is turned off. 
2 Insert the Panther+ board into the clips on the LSI baseboard and 
push until the Panther+ board is firmly latched into place. 
 
 
3 Lock the clips to secure the Panther+ board in place. 
  


                                                               
 
 
34 Wiwynn Honey Badger User Manual 
3.8 Replacing the Memory 
3.8.1 Removing the Memory 
1 Remove the Panther+ board (see Removing the Panther+ Board 
on page 31). 
2 Open the locking clips to release the memory module.  
 
3 Gently pull the memory module upward to remove it from the 
memory slot. 
 
4 Repeat steps 1 and 2 until you have removed all the memory 
modules from the top and bottom sides of the Panther+ board. 
 
 


                          
 
 
Wiwyynn Honey Badger User Manual 35 
3.8.2 Installing the Memory 
1 Insert the memory module into the memory slot on the Panther+ 
board.  
 
2 Gently press the memory module downward until the locking clips 
latch into place. 
 
3 Repeat steps 1 and 2 until you have installed all the memory 
modules on the top and bottom sides of the Panther+ board. 
4 Install the Panther+ board (see Installing the Panther+ Board on 
page 33). 
  


                                                               
 
 
36 Wiwynn Honey Badger User Manual 
3.9 Replacing the mSATA SSD Module 
3.9.1 Removing the mSATA SSD Module 
1 Remove the Panther+ board (see Removing the Panther+ Board 
on page 31). 
2 Push the two corners of the green plastic holder to release the 
mSATA SSD module. 
 
 
3 Remove the mSATA SSD module from the Panther+ board. 
 


                          
 
 
Wiwyynn Honey Badger User Manual 37 
3.9.2 Installing the mSATA SSD Module 
1 Insert the mSATA SSD module into its connector.  
 
 
2 Gently press the mSATA module until it latches into place. 
 
3 Install the Panther+ board (see Installing the Panther+ Board on 
page 33). 
  


                                                               
 
 
38 Wiwynn Honey Badger User Manual 
3.10 Replacing the M.2 SSD Module 
3.10.1 Removing the M.2 SSD Module 
1 Remove the Panther+ board (see Removing the Panther+ Board 
on page 31). 
2 Pry the green plastic holder to release the M.2 SSD module. 
 
 
3 Remove the M.2 SSD module from the Panther+ board. 
 


                          
 
 
Wiwyynn Honey Badger User Manual 39 
3.10.2 Installing the M.2 SSD Module 
1 Insert the M.2 SSD module into its connector.  
 
 
2 Press and hold the M.2 SSD module (1), then close the green 
plastic holder (2) to secure the M.2 SSD module in place. 
 
3 Install the Panther+ board (see Installing the Panther+ Board on 
page 33). 


                                                               
 
 
40 Wiwynn Honey Badger User Manual 
3.11 Replacing the LSI Baseboard 
 WARNING 
The heat sink on the LSI baseboard may be hot. 
To avoid possible burns, do not touch the heat 
sink. 
 
3.11.1 Removing the LSI Baseboard 
1 Loosen the thumbscrew securing the LSI baseboard to the HDD 
tray.  
 
2 Use the two tabs to pull out the LSI baseboard from the HDD tray. 
 
3 Remove the Panther+ board if it is still attached to the LSI 
baseboard (see steps 2 and 3 in Removing the Panther+ Board 
on page 31). 


                          
 
 
Wiwyynn Honey Badger User Manual 41 
3.11.2 Installing the LSI Baseboard 
1 Install the Panther+ board (see steps 2 and 3 in Installing the 
Panther+ Board on page 33). 
2 Insert the LSI baseboard into the HDD tray. 
 
 
3 Secure the LSI baseboard to the HDD tray by tightening the 
thumbscrew. 
 
  


                                                               
 
 
42 Wiwynn Honey Badger User Manual 
3.12 Replacing the Mezzanine Card 
3.12.1 Removing the Mezzanine Card 
1 Remove the LSI baseboard (see Removing the LSI Baseboard on 
page 40). 
2 Pinch the two retainer plugs (1) and press the two latches (2) to 
remove the mezzanine card (3). 
 
  


                          
 
 
Wiwyynn Honey Badger User Manual 43 
3.12.2 Installing the Mezzanine Card 
1 Align the holes on the mezzanine card with the corresponding 
retainer plugs and posts on the LSI baseboard. 
2 Press down the mezzanine card gently until it latches into place. 
 
3 Install the LSI baseboard (see Installing the LSI Baseboard on 
page 41). 
  


                                                               
 
 
44 Wiwynn Honey Badger User Manual 
3.13 Replacing the Battery 
 WARNING 
There is a danger of explosion if the battery is 
incorrectly replaced. Replace only with the same 
or equivalent type recommended by the 
equipment manufacturer. 
 
3.13.1 Removing the Battery 
1 Remove the LSI baseboard (see Removing the LSI Baseboard on 
page 40). 
2 Push the battery clip (1) and remove the battery (2) from its holder. 
 
  


                          
 
 
Wiwyynn Honey Badger User Manual 45 
3.13.2 Installing the Battery 
1 Insert the battery into the battery holder and push until the battery 
is properly seated. 
 
2 Install the LSI baseboard (see Installing the LSI Baseboard on 
page 41). 
 
 
  


                                                               
 
 
46 Wiwynn Honey Badger User Manual 
3.14 Replacing the SAS Expander Board 
3.14.1 Removing the SAS Expander Board 
1 Loosen the thumbscrew securing the SAS expander board to the 
HDD tray. 
 
2 Use the two tabs to pull out the SAS expander board from the HDD 
tray.     
 
 
 


                          
 
 
Wiwyynn Honey Badger User Manual 47 
3.14.2 Installing the SAS Expander Board 
1 Insert the SAS expander board into the HDD tray. 
 
 
2 Secure the SAS expander board to the HDD tray by tightening the 
thumbscrew.  
 
NOTE: Only the inboard thumbscrew is used; the thumbscrew 
under the release lever is not screwed into the tray. 
 
  


                                                               
 
 
48 Wiwynn Honey Badger User Manual 
3.15 Replacing the Hard Disk Drives 
3.15.1 Removing the Hard Disk Drive 
1 Lift the tabs to release the latch handles that secure the HDD tray 
to the chassis. 
 
2 Pull out the HDD tray from the chassis using both hands. 
 


                          
 
 
Wiwyynn Honey Badger User Manual 49 
3 Press the latch that secures the HDD cover to the tray (1) and lift 
up the HDD cover (2). 
 
4 Slide the HDD to disengage it from its connector and remove the 
HDD from the HDD tray. 
 
  


                                                               
 
 
50 Wiwynn Honey Badger User Manual 
3.15.2 Installing the Hard Disk Drive 
1 Insert the HDD into the tray and slide it toward the connector until it 
latches into place.    
 
2 Push down the HDD cover until it latches into place. DO NOT slam 
the HDD cover in place – apply pressure to the green latch while 
pushing the cover downwards, then release the green latch to 
engage the tray. Pushing the cover into place without doing this 
may result in shock which may damage neighboring HDDs. 
Applying pressure to the HDD cover will cause unbalanced force, 
this may result in latch non- engagement to the tray. 
 


                          
 
 
Wiwyynn Honey Badger User Manual 51 
3 Push the HDD tray all the way into the chassis using both hands.  
 
4 Push the latch handles until they lock into place.  
 


                                                               
 
 
52 Wiwynn Honey Badger User Manual 
3.16 Replacing the Power Cable 
3.16.1 Removing the Power Cable 
1 Remove the system from the rack (see Removing the System 
from the Rack on page 23). 
2 Remove the top cover (see Removing the Top Cover on page 
27). 
3 Disconnect the power cable from the drive plane board. 
 
  


                          
 
 
Wiwyynn Honey Badger User Manual 53 
4 Remove the cable clips that secure the power cable to the guide 
rail. 
 
5 Disconnect the power cable from the fan controller board. 
 
 
 
  


                                                               
 
 
54 Wiwynn Honey Badger User Manual 
3.16.2 Installing the Power Cable 
1 Connect the power cable to the fan controller board. 
 
 
2 Secure the power cable to the guide rail using cable clips. 
 
 
Note:  Make sure that the green cables are placed at the upper 
side of the guard rail housing. 


                          
 
 
Wiwyynn Honey Badger User Manual 55 
3 Connect the power cable to the drive plane board. 
 
 
4 Install the top cover (see Installing the Top Cover on page 28). 
5 Install the system into the rack (see Installing the System into the 
Rack on page 25).  


                                                               
 
 
56 Wiwynn Honey Badger User Manual 
3.17 Replacing the HDD Tray 
3.17.1 Removing the HDD Tray 
1 Lift the tabs to release the latch handles that secure the HDD tray 
to the chassis. 
 
2 Pull out the HDD tray from the chassis using both hands. 
 


                          
 
 
Wiwyynn Honey Badger User Manual 57 
3 Disconnect the power cable from the drive plane board. 
 
 
4 Loosen the thumbscrew securing the HDD tray to the guide rail. 
 
  


                                                               
 
 
58 Wiwynn Honey Badger User Manual 
5 Push down the safety latches on both sides of the HDD tray (1), 
and then pull the HDD tray out of the chassis (2).  If the latches 
are not pushed down completely, or if the HDD tray cannot be 
pulled out, push the tray back into the chassis approximately 1/8” 
(3mm) and try again. 
 
  


                          
 
 
Wiwyynn Honey Badger User Manual 59 
3.17.2 Installing the HDD Tray 
1 Insert the HDD tray into the chassis, making sure the sliders are 
properly aligned with the rails in the chassis. 
 
 
2 Secure the HDD tray to the guide rail by tightening the thumbscrew. 
  


                                                               
 
 
60 Wiwynn Honey Badger User Manual 
3 Connect the power cable to the drive plane board. 
 
4 Press the HDD tray into the chassis until the handles latch into 
place. 
  


                          
 
 
Wiwyynn Honey Badger User Manual 61 
3.18 Replacing the Bus Bar Cables 
3.18.1 Removing the Bus Bar Cables 
1 Remove the system from the rack (see Removing the System 
from the Rack on page 23). 
2 Remove the top cover (see Removing the Top Cover on page 
27). 
3 Remove the fan modules (see Removing the Fan Module on 
page 29). 
4 Remove the power cables (see Removing the Power Cable on 
page 52). 
5 Remove the HDD trays (see Removing the HDD Tray on page 
56). 
6 Remove the five screws securing the bus bar cables to the fan 
controller board. 
 
  


                                                               
 
 
62 Wiwynn Honey Badger User Manual 
7 Use a torx screw driver to remove the four torx screws securing the 
bus bar cables to the chassis. 
 
 
 
8 Lift the bus bar cables off the chassis. 
  


                          
 
 
Wiwyynn Honey Badger User Manual 63 
3.18.2 Installing the Bus Bar Cables 
1 Place the bus bar cables into the chassis. 
 
   
2 Use a torx screwdriver to secure the bus bar cables to the chassis 
with four torx screws. 
 
 
 
  


                                                               
 
 
64 Wiwynn Honey Badger User Manual 
3 Secure the bus bar cables to the fan controller board using five 
screws.  
 
4 Install the HDD trays (see Installing the HDD Tray on page 59). 
5 Install the power cables (see Installing the Power Cable on page 
54). 
6 Install the fan modules (see Installing the Fan Module on page 
30). 
7 Install the top cover (see Installing the Top Cover on page 28). 
8 Install the system into the rack (see Installing the System into the 
Rack on page 25). 
  


                          
 
 
Wiwyynn Honey Badger User Manual 65 
3.19 Replacing the Fan Controller Board 
3.19.1 Removing the Fan Controller Board 
1 Remove the system from the rack (see Removing the System 
from the Rack on page 23). 
2 Remove the top cover (see Removing the Top Cover on page 
27). 
3 Remove the fan modules (see Removing the Fan Module on 
page 29). 
4 Remove the power cables (see Removing the Power Cable on 
page 52). 
5 Remove the HDD trays (see Removing the HDD Tray on page 
56). 
6 Remove the bus bar cables (see Removing the Bus Bar Cables 
on page 61). 
7 Remove the eight screws securing the fan controller board to the 
chassis. 
 
 
  


                                                               
 
 
66 Wiwynn Honey Badger User Manual 
8 Lift the fan controller board off the chassis. 
 
 
3.19.2 Installing the Fan Controller Board 
1 Place the fan controller board into the chassis. 
 
 
 


                          
 
 
Wiwyynn Honey Badger User Manual 67 
2 Secure the fan controller board to the chassis using eight screws. 
 
 
 
3 Install the bus bar cables (see Installing the Bus Bar Cables on 
page 63). 
4 Install the HDD trays (see Installing the HDD Tray on page 59). 
5 Install the power cables (see Installing the Power Cable on page 
53). 
6 Install the fan modules (see Installing the Fan Module on page 
30). 
7 Install the top cover (see Installing the Top Cover on page 28). 
8 Install the system into the rack (see Installing the System into the 
Rack on page 25). 
  


                                                               
 
 
68 Wiwynn Honey Badger User Manual 
3.20 Replacing the Power Transition Board 
3.20.1 Removing the Power Transition Board 
1 Remove the LSI baseboard (see Removing the LSI Baseboard on 
page 40). 
2 Remove the SAS expander board (see Removing the SAS 
Expander Board on page 46). 
3 Remove the hard disk drives (see Removing the Hard Disk Drive 
on page 48). 
4 Remove the HDD trays (see Removing the HDD Tray on page 
56). 
5 Turn the tray over to access the base of the tray. 
6 Remove the four screws securing the power transition board to the 
chassis. 
 
 
  


                          
 
 
Wiwyynn Honey Badger User Manual 69 
7 Detach the plastic ramp from the power transition board. 
 
8 Slide the power transition board to disengage it from the drive 
plane board, and then lift it off the chassis. 
 


                                                               
 
 
70 Wiwynn Honey Badger User Manual 
3.20.2 Installing the Power Transition Board 
1 Insert the power transition board into the chassis and slide it toward 
the drive plane board until it latches into place. 
 
 
2 Place the plastic ramp into the power transition board. 
 


                          
 
 
Wiwyynn Honey Badger User Manual 71 
3 Secure the power transition board to the chassis using four screws. 
 
 
4 Install the HDD trays (see Installing the HDD Tray on page 59). 
5 Install the hard disk drives (see Installing the Hard Disk Drive on 
page 50). 
6 Install the LSI baseboard (see page 41) and the SAS expander 
board (see page 47). 
  


                                                               
 
 
72 Wiwynn Honey Badger User Manual 
3.21 Replacing the Drive Plane Board 
3.21.1 Removing the Drive Plane Board 
1 Remove the LSI baseboard (see page 40) and the SAS expander 
board (see page 46). 
2 Remove the hard disk drives (see Removing the Hard Disk Drive 
on page 48). 
3 Remove the HDD trays (see Removing the HDD Tray on page 
56). 
4 Remove the power transition board (see Removing the Power 
Transition Board on page 68). 
5 Remove the thirteen screws securing the drive plane board to the 
chassis. 
 
 
6 Remove the drive plane board from the chassis 
 


                          
 
 
Wiwyynn Honey Badger User Manual 73 
3.21.2 Installing the Drive Plane Board 
1 Place the drive plane board into the chassis. 
 
2 Secure the drive plane board to the chassis using thirteen screws. 
 
 
3 Install the power transition board (see Installing the Power 
Transition Board on page 70). 
4 Install the HDD trays (see Installing the HDD Tray on page 59). 
5 Install the hard disk drives (see Installing the Hard Disk Drive on 
page 50). 
6 Install the LSI baseboard (see page 41) and the SAS expander 
board (see page 47). 


                                                               
 
 
74 Wiwynn Honey Badger User Manual 
3.22 Debug Card 
3.22.1 Sub-System Selection for Debug Card 
As a storage server, Honey Badger contains two sub-systems. One is the 
CPU system and the other is the storage system. Each sub-system has a 
7-segment LED for displaying two-digit error codes and a reset switch to 
trigger a sub-system reset. 
Use the slide switch located beside the baseboard debug card connector 
to select which debug code to be displayed on the Honey Badger debug 
card.  Manufacturer’s default setting is POST code. 
3.22.2 Installing Debug Card 
1 Locate the ports for installing the debug card.  
 
  


                          
 
 
Wiwyynn Honey Badger User Manual 75 
2 Install the debug card. 
 
3 Connect the serial cable from the debug card to any USB port on 
your computer.  
  


                                                               
 
 
76 Wiwynn Honey Badger User Manual 
4. Firmware Update 
1. BMC Firmware Update 
BMC can implement remote BMC firmware update without requiring any 
physical input on the system. Remote update can be through 
Out-Of-Band by management network or through logging into local OS 
(CentOS) by data network. The BMC firmware update tool(s) support 
CentOS 5.2 and updated Facebook Kernel (FBK). 
The following steps show the alternate BMC firmware update by USB: 
1 Add this ipmitool command to enable virtual device (default is 
disable): 
 ipmitool raw 0x32 0xaa 0x00 
2 Key in; 
./Yafuflash –u USERID –p PASSW0RD –nw –ip 
xxx.xxx.xxx.xxx filename.ima 
NOTE: The IP address is based on the actual user environment 
Wait for the flash process to finish and BMC will restart automatically. 
A remote BMC firmware update may take a maximum of 5 minutes to 
complete. BMC firmware update and BMC reset processes do not require 
rebooting or powering down of the host system and have no impact on 
normal operation of host system. Wiwynn BMC is fully functional after 
firmware update and reset without requiring further configuration.  
BMC supports dual images for fail-over function. 
Normally, BCM always boots from image 1. If image 1 is damaged, 
u-boot selects image 2 to boot. After the user updates image 1, u-boot 



                          
 
 
Wiwyynn Honey Badger User Manual 77 
selects image 1 to boot again. 
2. FPGA Code Update 
BMC can implement remote FPGA code update without requiring any 
physical input on the system. Remote update can be through 
Out-Of-Band by management network or through logging into local OS 
(CentOS) by data network. The BMC firmware update tool(s) support 
CentOS 5.2 and updated Facebook Kernel (FBK). 
The following steps show the alternate FPGA code update by USB: 
1 Add this ipmitool command to enable virtual device (default is 
disable): 
ipmitool raw 0x32 0xaa 0x00 
2 Key in 
./Yafuflash -cd -cpld fpga.bin (at local OS) 
Wait for the flash process to finish and BMC will restart automatically. 
3. Remote BIOS Recovery via OOB 
BMC implements BIOS recovery mechanism through OOB. You can use 
this command to perform BIOS recovery: 
Key in:  
./Yafuflash-u USERID -p PASSW0RD -nw -ip 
xxx.xxx.xxx.xxx -d 2 ~/filename.iso 
NOTE: The IP address is based on the actual user environment 
After issuing this command, BIOS recovery mechanism starts 
automatically. 



                                                               
 
 
78 Wiwynn Honey Badger User Manual 
The limitations are as follows: 
1 BIOS boot section should be alive. 
2 The image should be in ISO format. The ISO image includes also a 
CRC-32 checksum and BMC will check if the image is correct or not 
based it on. 
4. Expander Firmware Update via In-band SAS 
Interface 
NOTE: Wiwynn customers can download XTools from Wiwynn or 
contact Avago directly for license in using or downloading 
XTools. 
For 12G Expander: 
The 12G Expander requires the sas3xfw.fw and mfg.bin binary files to 
update the firmware via in-band SAS interface on the system. You need 
to login to the local OS (CentOS) through the data network. The 12G 
Expander firmware update script uses Avago 12G XTools that support 
CentOS 6.x. 
For example: Expander SAS ID is 570e28402007d0ff 
1 Key in this command to update the expander firmware: 
./g3Xflash -i 570e28402007d0ff -y down fw sas3xfw.fw 
Wait for the flash process to finish. 
2 Key in this command to update the expander configuration region: 
./g3Xflash -i 570e28402007d0ff -y down mfg mfg.bin 3 
Wait for the flash process to finish. 



                          
 
 
Wiwyynn Honey Badger User Manual 79 
3 Key in this command to reset the expander and apply the new 
expander firmware: 
./g3Xflash -i 570e28402007d0ff -y reset exp 
Wait for at least one minute. 
For 6G Expander: 
The 6G Expander requires the sas2xfw.fw and mfg.bin binary files to 
update the firmware via in-band SAS interface on the system. You need 
to login to the local OS (CentOS) through the data network. The 6G 
Expander firmware update script uses Avago 6G XTools that support 
CentOS 6.x. 
For example: Expander SAS ID is 570e28402007d0ff 
1 Key in this command to update the expander firmware 
./xflash -i 570e28402007d0ff -y down fw sas2xfw.fw 1 
./xflash -i 570e28402007d0ff -y down fw sas2xfw.fw 2 
Wait for the flash process to finish. 
2 Key in this command to update the expander configuration region 
./xflash -i 570e28402007d0ff -y down mfg mfg.bin 3 
Wait for the flash process to finish. 
3 Key in this command to reset the expander and apply the new 
expander firmware: 
./xflash -i 570e28402007d0ff -y reset exp 
Wait for at least one minute.  



                                                               
 
 
80 Wiwynn Honey Badger User Manual 
5. Wiwynn Supported SES Pages 
Wiwynn SAS Expander firmware follows SES (SCSI Enclosure Services) 
standard so that supported SES pages can be retrieved by opening 
source utility such as Linux sg_ses tool. 
The following examples show you how to retrieve the status of some SES 
pages via Linux sg_ses tool. 
 
1. Get the status of SES page0 
[root@localhost ~]# sg_ses -p 0 /dev/sg16 
  wiwynn    HB2U              0415  
Supported diagnostic pages: 
  Supported Diagnostic Pages [sdp] [0x0] 
  Configuration (SES) [cf] [0x1] 
  Enclosure Status/Control (SES) [ec,es] [0x2] 
  String In/Out (SES) [str] [0x4] 
  Threshold In/Out (SES) [th] [0x5] 
  Element Descriptor (SES) [ed] [0x7] 
  Additional Element Status (SES-2) [aes] [0xa] 
  Download Microcode (SES-2) [dm] [0xe] 
 
2. Get the status of SES page1 
[root@localhost ~]# sg_ses -p 1 /dev/sg16 
    wiwynn    HB2U              0415  
Configuration diagnostic page: 
  number of secondary subenclosures: 0 
  generation code: 0x0 
  enclosure descriptor list 



                          
 
 
Wiwyynn Honey Badger User Manual 81 
    Subenclosure identifier: 0 (primary) 
      relative ES process id: 1, number of ES processes: 1 
      number of type descriptor headers: 8 
      enclosure logical identifier (hex): 570e28402007d0ff 
      enclosure vendor: wiwynn    product: HB2U        rev: 0404  
      vendor-specific data: 
        23 04 04 15 00 00 00 00 
  type descriptor header/text list 
    Element type: Array device slot, subenclosure id: 0 
      number of possible elements: 15 
      text: ArrayDevicesInSubEnclsr0 
Element type: SAS connector, subenclosure id: 0 
      number of possible elements: 19 
      text: ConnectorsInSubEnclsr0 
    Element type: Cooling, subenclosure id: 0 
      number of possible elements: 12 
      text: CoolingElementInSubEnclsr0 
    Element type: Temperature sensor, subenclosure id: 0 
      number of possible elements: 34 
      text: TempSensorsInSubEnclsr0 
    Element type: Voltage sensor, subenclosure id: 0 
      number of possible elements: 25 
      text: VoltageSensorsInSubEnclsr0 
    Element type: Current sensor, subenclosure id: 0 
      number of possible elements: 3 
      text: CurrentSensorsInSubEnclsr0 
    Element type: Enclosure, subenclosure id: 0 
      number of possible elements: 1 
      text: EnclosureElementInSubEnclsr0 



                                                               
 
 
82 Wiwynn Honey Badger User Manual 
    Element type: SAS expander, subenclosure id: 0 
      number of possible elements: 1 
      text: LSI SAS Expander 
 
3. Get the status of SES page2 
[root@localhost ~]# sg_ses -p 2 /dev/sg16 
  wiwynn    HB2U              0415  
  Primary enclosure logical identifier (hex): 5f80f41f1bbbbbff 
Enclosure Status diagnostic page: 
  INVOP=0, INFO=1, NON-CRIT=1, CRIT=1, UNRECOV=0 
  generation code: 0x0 
  status descriptor list 
    Element type: Array device slot, subenclosure id: 0 [ti=0] 
      Overall descriptor: 
        Predicted failure=0, Disabled=0, Swap=0, status: Unsupported 
        OK=0, Reserved device=0, Hot spare=0, Cons check=0 
        In crit array=0, In failed array=0, Rebuild/remap=0, R/R abort=0 
        App client bypass A=0, Do not remove=0, Enc bypass A=0, Enc bypass 
B=0 
        Ready to insert=0, RMV=0, Ident=0, Report=0 
        App client bypass B=0, Fault sensed=0, Fault reqstd=0, Device off=0 
        Bypassed A=0, Bypassed B=0, Dev bypassed A=0, Dev bypassed B=0 
      Element 0 descriptor: 
        Predicted failure=0, Disabled=0, Swap=0, status: OK 
        OK=0, Reserved device=0, Hot spare=0, Cons check=0 
        In crit array=0, In failed array=0, Rebuild/remap=0, R/R abort=0 
        App client bypass A=0, Do not remove=0, Enc bypass A=0, Enc bypass 
B=0 
        Ready to insert=0, RMV=0, Ident=0, Report=0 



                          
 
 
Wiwyynn Honey Badger User Manual 83 
        App client bypass B=0, Fault sensed=0, Fault reqstd=0, Device off=0 
        Bypassed A=0, Bypassed B=0, Dev bypassed A=0, Dev bypassed B=0 
      Element 1 descriptor: 
        Predicted failure=0, Disabled=0, Swap=0, status: OK 
        OK=0, Reserved device=0, Hot spare=0, Cons check=0 
        In crit array=0, In failed array=0, Rebuild/remap=0, R/R abort=0 
        App client bypass A=0, Do not remove=0, Enc bypass A=0, Enc bypass 
B=0 
        Ready to insert=0, RMV=0, Ident=0, Report=0 
        App client bypass B=0, Fault sensed=0, Fault reqstd=0, Device off=0 
        Bypassed A=0, Bypassed B=0, Dev bypassed A=0, Dev bypassed B=0 
 ...... 
 ...... 
 
    Element type: SAS connector, subenclosure id: 0 [ti=1] 
      Overall descriptor: 
        Predicted failure=0, Disabled=0, Swap=0, status: Unsupported 
        Ident=0, No information 
        Connector physical link=0x0, Fail=0 
      Element 0 descriptor: 
        Predicted failure=0, Disabled=0, Swap=0, status: OK 
        Ident=0, SAS Drive backplane receptacle (SFF-8482) [max 2 phys] 
        Connector physical link=0x0, Fail=0 
      Element 1 descriptor: 
        Predicted failure=0, Disabled=0, Swap=0, status: OK 
        Ident=0, SAS Drive backplane receptacle (SFF-8482) [max 2 phys] 
        Connector physical link=0x0, Fail=0 
 ...... 
 ...... 



                                                               
 
 
84 Wiwynn Honey Badger User Manual 
  
    Element type: Cooling, subenclosure id: 0 [ti=2] 
      Overall descriptor: 
        Predicted failure=0, Disabled=0, Swap=0, status: Unsupported 
        Ident=0, Hot swap=0, Fail=0, Requested on=0, Off=0 
        Actual speed=0 rpm, Fan stopped 
      Element 0 descriptor: 
        Predicted failure=0, Disabled=0, Swap=0, status: OK 
        Ident=0, Hot swap=0, Fail=0, Requested on=0, Off=0 
        Actual speed=6220 rpm, Fan at third highest speed 
      Element 1 descriptor: 
        Predicted failure=0, Disabled=0, Swap=0, status: OK 
        Ident=0, Hot swap=0, Fail=0, Requested on=0, Off=0 
        Actual speed=6420 rpm, Fan at third highest speed 
 ...... 
 ...... 
 
    Element type: Temperature sensor, subenclosure id: 0 [ti=3] 
      Overall descriptor: 
        Predicted failure=0, Disabled=0, Swap=0, status: Unsupported 
        Ident=0, Fail=0, OT failure=0, OT warning=0, UT failure=0 
        UT warning=0 
        Temperature: <reserved> 
      Element 0 descriptor: 
        Predicted failure=0, Disabled=0, Swap=0, status: OK 
        Ident=0, Fail=0, OT failure=0, OT warning=0, UT failure=0 
        UT warning=0 
        Temperature=46 C 
      Element 1 descriptor: 



                          
 
 
Wiwyynn Honey Badger User Manual 85 
        Predicted failure=0, Disabled=0, Swap=0, status: OK 
        Ident=0, Fail=0, OT failure=0, OT warning=0, UT failure=0 
        UT warning=0 
        Temperature=54 C 
 ...... 
 ...... 
 
    Element type: Voltage sensor, subenclosure id: 0 [ti=4] 
      Overall descriptor: 
        Predicted failure=0, Disabled=0, Swap=0, status: Unsupported 
        Ident=0, Fail=0,  Warn Over=0, Warn Under=0, Crit Over=0  
        Crit Under=0 
        Voltage: 0.00 volts 
      Element 0 descriptor: 
        Predicted failure=0, Disabled=0, Swap=0, status: OK 
        Ident=0, Fail=0,  Warn Over=0, Warn Under=0, Crit Over=0  
        Crit Under=0 
        Voltage: 12.37 volts 
      Element 1 descriptor: 
        Predicted failure=0, Disabled=0, Swap=0, status: OK 
        Ident=0, Fail=0,  Warn Over=0, Warn Under=0, Crit Over=0  
        Crit Under=0 
        Voltage: 12.22 volts 
 ...... 
 ...... 
  
    Element type: Current sensor, subenclosure id: 0 [ti=5] 
      Overall descriptor: 
        Predicted failure=0, Disabled=0, Swap=0, status: Unsupported 



                                                               
 
 
86 Wiwynn Honey Badger User Manual 
        Ident=0, Fail=0, Warn Over=0, Crit Over=0 
        Current: 0.00 amps 
      Element 0 descriptor: 
        Predicted failure=0, Disabled=0, Swap=0, status: OK 
        Ident=0, Fail=0, Warn Over=0, Crit Over=0 
        Current: 2.11 amps 
      Element 1 descriptor: 
        Predicted failure=0, Disabled=0, Swap=0, status: OK 
        Ident=0, Fail=0, Warn Over=0, Crit Over=0 
        Current: 0.92 amps 
      Element 2 descriptor: 
        Predicted failure=0, Disabled=0, Swap=0, status: OK 
        Ident=0, Fail=0, Warn Over=0, Crit Over=0 
        Current: 20.53 amps 
 
    Element type: Enclosure, subenclosure id: 0 [ti=6] 
      Overall descriptor: 
        Predicted failure=0, Disabled=0, Swap=0, status: Unsupported 
        Ident=0, Time until power cycle=0, Failure indication=0 
        Warning indication=0, Requested power off duration=0 
        Failure requested=0, Warning requested=0 
      Element 0 descriptor: 
        Predicted failure=0, Disabled=0, Swap=0, status: OK 
        Ident=0, Time until power cycle=0, Failure indication=0 
        Warning indication=0, Requested power off duration=0 
        Failure requested=0, Warning requested=0 
 
    Element type: SAS expander, subenclosure id: 0 [ti=7] 
      Overall descriptor: 



                          
 
 
Wiwyynn Honey Badger User Manual 87 
        Predicted failure=0, Disabled=0, Swap=0, status: Unsupported 
        Ident=0, Fail=0 
      Element 0 descriptor: 
        Predicted failure=0, Disabled=0, Swap=0, status: OK 
        Ident=0, Fail=0 
 
 
4. Get the status of SES page7 
[root@localhost ~]# sg_ses -p 7 /dev/sg16 
  wiwynn    HB2U              0415  
  Primary enclosure logical identifier (hex): 5f80f41f1bbbbbff 
Element Descriptor In diagnostic page: 
  generation code: 0x0 
  element descriptor by type list 
    Element type: Array device slot, subenclosure id: 0 [ti=0] 
      Overall descriptor: ArrayDevicesInSubEnclsr0 
      Element 0 descriptor: ArrayDevice00 
      Element 1 descriptor: ArrayDevice01 
   ...... 
   ...... 
 
    Element type: SAS connector, subenclosure id: 0 [ti=1] 
      Overall descriptor: ConnectorsInSubEnclsr0 
      Element 0 descriptor: Connector00 
      Element 1 descriptor: Connector01 
   ...... 
   ...... 
 
    Element type: Cooling, subenclosure id: 0 [ti=2] 



                                                               
 
 
88 Wiwynn Honey Badger User Manual 
      Overall descriptor: CoolingElementInSubEnclsr0 
      Element 0 descriptor: Fan_1_Front 
      Element 1 descriptor: Fan_1_Rear 
   ...... 
   ...... 
 
    Element type: Temperature sensor, subenclosure id: 0 [ti=3] 
      Overall descriptor: TempSensorsInSubEnclsr0 
      Element 0 descriptor: HBB_SAS_CTRL_Temp 
      Element 1 descriptor: HBB_Expander_Temp 
   ...... 
   ...... 
 
    Element type: Voltage sensor, subenclosure id: 0 [ti=4] 
      Overall descriptor: VoltageSensorsInSubEnclsr0 
      Element 0 descriptor: HBB_Voltage_12.5V_HotSwap 
      Element 1 descriptor: HBB_Voltage_12.5V 
   ...... 
   ...... 
    
    Element type: Current sensor, subenclosure id: 0 [ti=5] 
      Overall descriptor: CurrentSensorsInSubEnclsr0 
      Element 0 descriptor: HBB_Current 
      Element 1 descriptor: PPC_Current 
      Element 2 descriptor: FCB_Current 
 
    Element type: Enclosure, subenclosure id: 0 [ti=6] 
      Overall descriptor: EnclosureElementInSubEnclsr0 
      Element 0 descriptor: EnclosureElement01 



                          
 
 
Wiwyynn Honey Badger User Manual 89 
 
    Element type: SAS expander, subenclosure id: 0 [ti=7] 
      Overall descriptor: LSI SAS Expander 
      Element 0 descriptor: Top ExpanderA 
 
 
5. Get the status of SES page10 
[root@localhost ~]# sg_ses -p 10 /dev/sg16 
  wiwynn    HB2U              0415  
  Primary enclosure logical identifier (hex): 570e28402007d0ff 
Additional element status diagnostic page: 
  generation code: 0x0 
  additional element status descriptor list 
    Element type: Array device slot, subenclosure id: 0 [ti=0] 
      Element index: 0  eiioe=0  
        Transport protocol: SAS 
        number of phys: 1, not all phys: 0, device slot number: 0 
        phy index: 0 
          device type: end device 
          initiator port for: 
          target port for: SSP 
          attached SAS address: 0x570e28402007d0ff 
          SAS address: 0x5000cca0243792dd 
          phy identifier: 0x0 
      Element index: 1  eiioe=0  
        Transport protocol: SAS 
        number of phys: 1, not all phys: 0, device slot number: 1 
        phy index: 0 
          device type: end device 



                                                               
 
 
90 Wiwynn Honey Badger User Manual 
          initiator port for: 
          target port for: SSP 
          attached SAS address: 0x570e28402007d0ff 
          SAS address: 0x5000cca024370f01 
          phy identifier: 0x0 
   ...... 
   ...... 
    
    Element index: 14  eiioe=0  
        Transport protocol: SAS 
        number of phys: 1, not all phys: 0, device slot number: 14 
        phy index: 0 
          device type: end device 
          initiator port for: 
          target port for: SSP 
          attached SAS address: 0x570e28402007d0ff 
          SAS address: 0x5000cca02437939d 
          phy identifier: 0x0 
  



                          
 
 
Wiwyynn Honey Badger User Manual 91 
6. Checkpoints and Errors 
6.1 Error Code Definition 
This section lists the full definitions of the Honey Badger storage system 
error codes. These codes are displayed on the debug card when switch 
button selected and are stored in the storage system event log. 
To get all error code via sg_read_buffer command with buffer id 0x76 as 
follows. 
Example 1. Current status is “No error” means byte 0 (error code 0) will 
be set as 1. 
# sg_read_buffer --mode=1 --id=0x76 -l 100 /dev/sgX 
00     01 00 00 00 00 00 00 00  00 00 00 00 00 00 00 00 
10     00 00 00 00 00 00 00 00  00 00 00 00 00 00 00 00 
20     00 00 00 00 00 00 00 00  00 00 00 00 00 00 00 00 
30     00 00 00 00 00 00 00 00  00 00 00 00 00 00 00 00 
40     00 00 00 00 00 00 00 00  00 00 00 00 00 00 00 00 
50     00 00 00 00 00 00 00 00  00 00 00 00 00 00 00 00 
60     00 00 00 00 
 
Example 2. Current status has error code 50 & 94 means byte 50 & 94 
(error code 50 & 94) will be set as 1. 
# sg_read_buffer --mode=1 --id=0x76 -l 100 /dev/sgX 
 00     00 00 00 00 00 00 00 00  00 00 00 00 00 00 00 00 
 10     00 00 00 00 00 00 00 00  00 00 00 00 00 00 00 00 
 20     00 00 00 00 00 00 00 00  00 00 00 00 00 00 00 00 
 30     00 00 01 00 00 00 00 00  00 00 00 00 00 00 00 00 
 40     00 00 00 00 00 00 00 00  00 00 00 00 00 00 00 00 
 50     00 00 00 00 00 00 00 00  00 00 00 00 00 00 01 00 
 60     00 00 00 00 
 
where /dev/sgX should be an SES device (such as sg1, sg2, ...) 
 



                                                               
 
 
92 Wiwynn Honey Badger User Manual 
Error 
Code Description Condition Event Log 
0 No error   
1 Reserved   
2 Reserved   
3 I2C bus A crash Cannot query I2C device 
in I2C bus A 
Critical-I2C Bus ID 
0 Crash 
4 I2C bus B crash Cannot query I2C device 
in I2C bus B 
Critical-I2C Bus ID 
1 Crash 
5 I2C bus C crash Cannot query I2C device 
in I2C bus C 
Critical-I2C Bus ID 
2 Crash 
6 I2C bus D crash Cannot query I2C device 
in I2C bus D 
Critical-I2C Bus ID 
3 Crash 
7 I2C bus E crash Cannot query I2C device 
in I2C bus E 
Critical-I2C Bus ID 
4 Crash 8 Reserved   
9 Reserved   
10 Reserved   
11 Fan 1 front fault Cannot query fan speed 
in fan module 1 front 
Critical-Cooling ID 0 
Fail,X(RPM) 
12 Fan 1 rear fault Cannot query fan speed 
in fan module 1 rear 
Critical-Cooling ID 1 
Fail,X(RPM) 
13 Fan 2 front fault Cannot query fan speed 
in fan module 2 front 
Critical-Cooling ID 2 
Fail,X(RPM) 
14 Fan 2 rear fault Cannot query fan speed 
in fan module 2 rear 
Critical-Cooling ID 3 
Fail,X(RPM) 
15 Fan 3 front fault Cannot query fan speed 
in fan module 3 front 
Critical-Cooling ID 4 
Fail,X(RPM) 
16 Fan 3 rear fault Cannot query fan speed 
in fan module 3 rear 
Critical-Cooling ID 5 
Fail,X(RPM) 
17 Fan 4 front fault Cannot query fan speed 
in fan module 4 front 
Critical-Cooling ID 6 
Fail,X(RPM) 



                          
 
 
Wiwyynn Honey Badger User Manual 93 
Error 
Code Description Condition Event Log 
18 Fan 4 rear fault Cannot query fan speed 
in fan module 4 rear 
Critical-Cooling ID 7 
Fail,X(RPM) 
19 Fan 5 front fault Cannot query fan speed in 
fan module 5 front 
Critical-Cooling ID 8 
Fail,X(RPM) 
20 Fan 5 rear fault Cannot query fan speed in 
fan module 5 rear 
Critical-Cooling ID 9 
Fail,X(RPM) 
21 Fan 6 front fault Cannot query fan speed in 
fan module 6 front 
Critical-Cooling ID 
10 Fail,X(RPM) 
22 Fan 6 rear fault Cannot query fan speed in 
fan module 6 rear 
Critical-Cooling ID 11 
Fail,X(RPM) 
23 Reserved   
24 Reserved   
25 PPC CPU Temp. 
warning 
Temperature over critical 
threshold 
Critical-Temp. ID 7 
Fail,Temp=X(C) 
26 PPC DIMM A0 
Temp. warning 
Temperature over critical 
threshold 
Critical-Temp. ID 8 
Fail,Temp=X(C) 
27 PPC DIMM A1 
Temp. warning 
Temperature over critical 
threshold 
Critical-Temp. ID 9 
Fail,Temp=X(C) 
28 PPC DIMM B0 
Temp. warning 
Temperature over critical 
threshold 
Critical-Temp. ID 10 
Fail,Temp=X(C) 
29 PPC DIMM B1 
Temp. warning 
Temperature over critical 
threshold 
Critical-Temp. ID 11 
Fail,Temp=X(C) 
30 PPC Ambient 
Temp.  
Temperature over critical 
threshold 
Critical-Temp. ID 12 
Fail,Temp=X(C) 31 DPB temp. 1 
warning 
Temperature over critical 
threshold 
Critical-Temp. ID 13 
Fail,Temp=X(C) 32 DPB temp. 2 
warning 
Temperature over critical 
threshold 
Critical-Temp. ID 14 
Fail,Temp=X(C) 33 DPB temp. 3 
warning 
Temperature over critical 
threshold 
Critical-Temp. ID 15 
Fail,Temp=X(C) 34 DPB temp. 4 
warning 
Temperature over critical 
threshold 
Critical-Temp. ID 16 
Fail,Temp=X(C) 35 FCB BJT temp. 1 
warning 
Temperature over critical 
threshold 
Critical-Temp. ID 17 
Fail,Temp=X(C) 



                                                               
 
 
94 Wiwynn Honey Badger User Manual 
Error 
Code Description Condition Event Log 
36 FCB BJT temp. 2 
warning 
Temperature over critical 
threshold 
Critical-Temp. ID 18 
Fail,Temp=X(C) 
37 HBB SAS CTRL 
Temp.  
Temperature over critical 
threshold 
Critical-Temp. ID 0 
Fail,Temp=X(C) 38 HBB Expander 
Temp.  
Temperature over critical 
threshold 
Critical-Temp. ID 1 
Fail,Temp=X(C) 39 HBB Ambient 
Temp.  
Temperature over critical 
threshold 
Critical-Temp. ID 2 
Fail,Temp=X(C) 40 Reserved   
41 Reserved   
42 Reserved   
43 PPC voltage 
warning 
Voltage over or under 
critical threshold 
Critical-Voltage ID ? 
Fail,V=X(mV) 
(ID : Voltage sensor 
on Panther+ Card) 
44 HBB voltage 
warning 
Voltage over or under 
critical threshold 
Critical-Voltage ID ? 
Fail,V=X(mV) 45 DPB voltage 
warning 
Voltage over or under 
critical threshold 
(ID : Voltage sensor 
on HBB) 
46 FCB voltage 
warning 
Voltage over or under 
critical threshold 
(ID : Voltage sensor 
on DPB) 
47 PPC current 
warning 
Current over or under 
critical threshold 
(ID : Voltage sensor 
on FCB) 
48 HBB current 
warning 
Current over or under 
critical threshold 
Critical-Current ID 1 
Fail,I=X(mA) 49 FCB current 
warning 
Current over or under 
critical threshold 
Critical-Current ID 2 
Fail,I=X(mA) 50 HDD0 SMART 
temp. warning 
HDD0 Temperature over 
critical threshold 
Critical-Temp. ID 19 
Fail,Temp=X(C) 
51 HDD1 SMART 
temp. warning 
HDD1 Temperature over 
critical threshold 
Critical-Temp. ID 20 
Fail,Temp=X(C) 
52 HDD2 SMART 
temp. warning 
HDD2 Temperature over 
critical threshold 
Critical-Temp. ID 21 
Fail,Temp=X(C) 
53 HDD3 SMART 
temp. warning 
HDD3 Temperature over 
critical threshold 
Critical-Temp. ID 22 
Fail,Temp=X(C) 
54 HDD4 SMART 
temp. warning 
HDD4 Temperature over 
critical threshold 
Critical-Temp. ID 23 
Fail,Temp=X(C) 



                          
 
 
Wiwyynn Honey Badger User Manual 95 
Error 
Code Description Condition Event Log 
55 HDD5 SMART 
temp. warning 
HDD5 Temperature over 
critical threshold 
Critical-Temp. ID 24 
Fail,Temp=X(C) 
56 HDD6 SMART 
temp. warning 
HDD6 Temperature over 
critical threshold 
Critical-Temp. ID 25 
Fail,Temp=X(C) 
57 HDD7 SMART 
temp. warning 
HDD7 Temperature over 
critical threshold 
Critical-Temp. ID 26 
Fail,Temp=X(C) 
58 HDD8 SMART 
temp. warning 
HDD8 Temperature over 
critical threshold 
Critical-Temp. ID 27 
Fail,Temp=X(C) 
59 HDD9 SMART 
temp. warning 
HDD9 Temperature over 
critical threshold 
Critical-Temp. ID 28 
Fail,Temp=X(C) 
60 HDD10 SMART 
temp. warning 
HDD10 Temperature over 
critical threshold 
Critical-Temp. ID 29 
Fail,Temp=X(C) 
61 HDD11 SMART 
temp. warning 
HDD11 Temperature over 
critical threshold 
Critical-Temp. ID 30 
Fail,Temp=X(C) 
62 HDD12 SMART 
temp. warning 
HDD12 Temperature over 
critical threshold 
Critical-Temp. ID 31 
Fail,Temp=X(C) 
63 HDD13 SMART 
temp. warning 
HDD13 Temperature over 
critical threshold 
Critical-Temp. ID 32 
Fail,Temp=X(C) 
64 HDD14 SMART 
temp. warning 
HDD14 Temperature over 
critical threshold 
Critical-Temp. ID 33 
Fail,Temp=X(C) 
65 HBB System 
Outlet Temp. 
Temperature over critical 
threshold 
Critical-Temp. ID 3 
Fail,Temp=X(C) 
66 HBB IOC Ambient 
Temp. 
Temperature over critical 
threshold 
Critical-Temp. ID 4 
Fail,Temp=X(C) 67 HBB Expander 
Ambient Temp. 
Temperature over critical 
threshold 
Critical-Temp. ID 5 
Fail,Temp=X(C) 
68 HBB Mezz 
Ambient Temp. 
Temperature over critical 
threshold 
Critical-Temp. ID 6 
Fail,Temp=X(C) 
69 Reserved     
70 HDD0 fault HDD0 Array Device 
Element status fault 
Critical-HDD Slot 0 
Status Fault 71 HDD1 fault HDD1 Array Device 
Element status fault 
Critical-HDD Slot 1 
Status Fault 



                                                               
 
 
96 Wiwynn Honey Badger User Manual 
Error 
Code Description Condition Event Log 
72 HDD2 fault HDD2 Array Device 
Element status fault 
Critical-HDD Slot 2 
Status Fault 73 HDD3 fault HDD3 Array Device 
Element status fault 
Critical-HDD Slot 3 
Status Fault 74 HDD4 fault HDD4 Array Device 
Element status fault 
Critical-HDD Slot 4 
Status Fault 75 HDD5 fault HDD5 Array Device 
Element status fault 
Critical-HDD Slot 5 
Status Fault 76 HDD6 fault HDD6 Array Device 
Element status fault 
Critical-HDD Slot 6 
Status Fault 77 HDD7 fault HDD7 Array Device 
Element status fault 
Critical-HDD Slot 7 
Status Fault 78 HDD8 fault HDD8 Array Device 
Element status fault 
Critical-HDD Slot 8 
Status Fault 79 HDD9 fault HDD9 Array Device 
Element status fault 
Critical-HDD Slot 9 
Status Fault 80 HDD10 fault HDD10 Array Device 
Element status fault 
Critical-HDD Slot 10 
Status Fault 81 HDD11 fault HDD11 Array Device 
Element status fault 
Critical-HDD Slot 11 
Status Fault 82 HDD12 fault HDD12 Array Device 
Element status fault 
Critical-HDD Slot 12 
Status Fault 83 HDD13 fault HDD13 Array Device 
Element status fault 
Critical-HDD Slot 13 
Status Fault 84 HDD14 fault HDD14 Array Device 
Element status fault 
Critical-HDD Slot 14 
Status Fault 85 Reserved   
86 Reserved   
87 Reserved   
88 Reserved   
89 Reserved   
90 External Mini-SAS 
link error 
Loss of SAS links (x1~x3) Critical-Connector ID 
12 Loss Link(s) 
91 Internal Mini-SAS 
link error 
Loss of SAS links (x1~x3) Critical-Connector ID 
13 Loss Link(s) 
92 Reserved   
93 Self tray be pulled 
out 
F/W detect self tray be 
pulled out 
Critical-Self Tray Be 
Pulled Out 
94 Peer tray be pulled 
out 
F/W detect peer tray be 
pulled out 
Critical-Peer Tray Be 
Pulled Out 
95 Reserved      



                          
 
 
Wiwyynn Honey Badger User Manual 97 
Error 
Code 
Description Condition Event Log 
96 Reserved      
97 Reserved     
98 Reserved     
99 Firmware and 
hardware not 
match 
Only show this error code 
when FW initialization  
and then FW will hang 
N/A 
 
 
  



                                                               
 
 
98 Wiwynn Honey Badger User Manual 
6.2 Post Code Table 
6.2.1 PEI Phase 
A. Progress Codes 
Normal: 
Checkpoint Description 
0x10 PEI Core is started. 
0x11 Pre-memory CPU initialization is started. 
0x15 Pre-memory North Bridge initialization is started. 
0x19 Pre-memory South Bridge initialization is started. 
0x2B Memory initialization. Serial Presence Detect (SPD) data 
reading. 
0x2C Memory initialization. Memory presence detection.  
0x2D Memory initialization. Programming memory timin g 
information. 
0x2E Memory initialization. Configuring memory.  
0x2F Memory initialization (other). 
0x30 Reserved for ASL. 
0x31 Memory installed. 
0x37 Post-Memory North Bridge initialization is started.  
0x3B 
 
Post-Memory South Bridge initialization is started.  
0x4F DXE IPL is started. 
0x60 DXE Core is started. 
 
  



                          
 
 
Wiwyynn Honey Badger User Manual 99 
Recovery: 
Checkpoint Description 
0xF0 Recovery condition triggered by firmware (Auto recovery)  
0xF1 Recovery condition triggered by user (Forced recovery)  
 0xF2 Recovery process started 
 0xF3 Recovery firmware image is found 
0xF4 Recovery firmware image is loaded 
B. Error Codes 
Normal: 
Checkpoint Description 
0x50 
 
Memory initialization error. Invalid memory type or 
incompatible memory speed 
 0x51 Memory initialization error. SPD reading has failed  
 0x52 Memory initialization error. Invalid memory size or memory 
modules do not match 
 0x53 Memory initialization error. No usable memory detected  
 0x54 Unspecified memory initialization error  
 0x55 Memory not installed 
 0x56 Invalid CPU type or Speed 
 0x57 CPU mismatch 
 0x58 CPU self-test failed or possible CPU cache error  
 0x59 CPU micro-code not found or micro-code update failed 
0x5A Internal CPU error 
 0x5B Reset PPI is not available 
  
  



                                                               
 
 
100 Wiwynn Honey Badger User Manual 
Recovery: 
Checkpoint Description 
0xF8 Recovery PPI is not available 
 0xF9 Recovery capsule is not found 
 0xFA Invalid recovery capsule 
  
6.2.2 DXE Phase 
A. Progress Codes 
Checkpoint Description 
0x60 DXE Core is started. 
0x61 NVRAM initialization. 
0x62 Installation of the South Bridge Runtime Services.  
0x63 CPU DXE initialization is started.  
0x68 PCI host bridge initialization. 
0x69 North Bridge DXE initialization is started.  
0x6A North Bridge DXE SMM initialization is started.  
0x70 South Bridge DXE initialization is started.  
0x71 South Bridge DXE SMM initialization is started.  
0x72 South Bridge devices initialization.  
0x78 ACPI module initialization. 
0x79 CSM initialization. 
0x90 Boot Device Selection (BDS) phase is started.  
0x91 Driver connecting is started. 
0x92 PCI Bus initialization is started.  
0x93 PCI Bus Hot Plug Controller Initialization.  
0x94 PCI Bus Enumeration. 
0x95 PCI Bus Request Resources. 
0x96 PCI Bus Assign Resources. 



                          
 
 
Wiwyynn Honey Badger User Manual 101 
Checkpoint Description 
0x97 Console Output devices connect. 
0x98 Console input devices connect. 
0x99 Super IO Initialization. 
0x9A USB initialization is started. 
0x9B USB Reset. 
0x9C USB Detect. 
0x9D USB Enable. 
0xA0 IDE initialization is started. 
0xA1 IDE Reset. 
0xA2 IDE Detect. 
0xA3 IDE Enable. 
0xA4 SCSI initialization is started. 
0xA5 SCSI Reset. 
0xA6 SCSI Detect. 
0xA7 SCSI Enable. 
0xA8 Setup Verifying Password. 
0xA9 Start of Setup. 
0xAB Setup Input Wait 
0xAD Ready To Boot event. 
0xAE Legacy Boot event. 
0xAF Exit Boot Services event. 
0xB0 Runtime Set Virtual Address MAP Begin.  
0xB1 Runtime Set Virtual Address MAP End.  
0xB2 Legacy Option ROM Initialization. 
0xB3 System Reset. 
0xB4 USB hot plug. 
0xB5 PCI bus hot plug. 
0xB6 Clean-up of NVRAM. 
0xB7 Configuration Reset (reset of NVRAM settings).  



                                                               
 
 
102 Wiwynn Honey Badger User Manual 
B. Error Codes 
Checkpoint Description 
0xD0 
 
CPU initialization error 
 0xD1 
 
North Bridge initialization error  
 0xD2 South Bridge initialization error  
 0xD3 PCI resource allocation error. Out of Resources  
 0xD4 No Space for Legacy Option ROM 
 0xD5 No Console Output Devices are found  
 0xD6 No Console Input Devices are found 
 0xD7 Invalid password 
 0xD8 Error loading Boot Option 
 0xD9 Boot Option failed 
 0xDA Flash update failed 
 0xDB Reset protocol is not available 
  
  



                          
 
 
Wiwyynn Honey Badger User Manual 103 
6.2.3 DIMM Post Code 
During the boot sequence , the BIOS initialize s and tests each DIMM 
module. If a module fails  initialization or does not pass the BIOS test, 
the following post codes will flash on the debug card to indicate which 
DIMM has failed. The display sequence will be “00”, DIMM location, 
error code and progress code, with 1 second delay for every code 
displayed. The BIOS shall repeat the disp lay sequence indefinitely to 
allow time for a technician to service the system.  
A. Error Codes 
Checkpoint Description 
0x01 Debug 
0x02 Detect DIMMs Failure 
0x03 Invalid Host IO Boundary 
0x04 Install PEI Memory Error. 
 0x05 Invalid Number of Channels 
0x06 RCVEN Margin is too low 
0x07 Invalid Memory Size Found 
0x08 Memory Size per channel above Max Supported  
0x09 Invalid VDD Configuration 
0x0A Illegal Voltage Configuration 
0x0B Invalid Strobe 
0x0C Invalid CPU Type 
0x0D Mailbox Error 
0x0E MemTest Error 
0x0F Warm Reset Error 
0x10 Error trying to get SPD data 
0x11 No DIMMs are Present 
0x12 Timing does not comply with JEDEC spec.  
 



                                                               
 
 
104 Wiwynn Honey Badger User Manual 
Checkpoint Description 
0x13 Detect DIMM Tasks Error 
0x14 Invalid Number of Ranks 
0x15 Invalid Number of DIMMs 
0x16 Error Configuring Memory 
0x17 Null Pointer Error 
0x18 GetSet Value exceeds limit 
0x19 Faulty Parts Tracking: Halt on Correctable Error  
0x1A Faulty Parts Tracking: Uncorrectable Error on CH0.  
0x1B MRC Center Not Found 
0x1C Victim Aggressor Invalid Pattern Index 
0x1D Invalid Margin Type 
0x1E TxVref Margin is below 5 Ticks 
0x1F Invalid Frequency 
0x20 Timeout waiting for RTOS_DONE from Punit  
 
B. Progress Codes 
Checkpoint Description 
0x12 Programs the Clock gating feature for memory controller  
0x13 Clear the self- refresh bits 
0x14 OEM track init completed 
0x42 Programs the DRAM timing and control registers  
0x44 Programs the bustlength mode registers  
0x45 Enables/ Disables the Low voltage in the DDRIO Unit  
0x50 Initialize the DDRIO PHY 
0xA0~0xB2 DDR PHY init tasks. DDRIO should be initialized and ready 
for training after these tasks are executed 
0x51 Enables the DDRIO CKE for each rank 
0x61 Programs the timing & control registers for memory 
controller 



                          
 
 
Wiwyynn Honey Badger User Manual 105 
Checkpoint Description 
0x62 Programs the memory mapping in the memory controller 
registers 
0x71 Wake command to DUNIT 
0x81 Set configuration for Pre-Jedec init 
0x82 Programs the Jedec init for a row of memory  
0x83 Programs miscellaneous registers required to be set after 
memory 
 
initialization 
0x90 Programs the PMI to be release by BUNIT  
0x91 Disables PMI 
0x92 Indicates when memory training initialization is complete  
0xB0 Handle rank overrides 
0xB1 Enable overrides on diffampen and odt  
0xB2 Sets write VREF prior to start all MRC training to a known 
value in order to avoid failures during early trainings.  
0xB3 Programs the PMI to be release by BUNIT  
0xB4 Enables PMI 
0xB5 Handle memory training 
0xB6 Overrides Vref 
0xBE Enables the BUNIT cache. Used after memory training to  
return to normal operation before MRC exits. 
0xC0 Reconfigures the DRP registers with accurate information 
about the DDR memory. 
0xD1 Programs the DDR timing control registers  
0xE1 This function configures the scrambler  
0xE2 Sets periodic resistive compensation 
0xE3 Indicates when memory training initialization is complete  
0xE4 Sends a wake command to DDR Memory 
0xE5 Modifies the refresh period 
0xE6 Programs the PMI to be release by BUNIT  
0xE8 Enables PMI 



                                                               
 
 
106 Wiwynn Honey Badger User Manual 
Checkpoint Description 
0xE9 Handle post training 
0xEA Sends 'PMOP' command to Punit, in order to set the 
desired Power Mode. 
0xF0 Executed prior to the memory testing, in order to do the 
proper setup 
0xF1 Memory testing 
0xF2 Develops the scrub memory functionality  
0xF3 Programs the PMI to be owned by BUNIT 
0xF4 Indicates when MRC has completed 
0xF5 De-asserts a DDR reset 
0xF6 Enables performance setup in the Bunit  
0xF7 Disables the High Precision Event Timer  
 